# SCM (Grand Teton) — schematic netlist excerpt (pin names and nets, part order shuffled) for the footprints in the layout excerpt that follows; sources: Cadence DE-HDL packaged netlist, KiCad conversion of 12092022_DA0F0TMDCD0_F0T_Management_Board_D_brd_V3_OCP.brd

C31  Q_CAP  0.1UF 25V 10% X7R  pkg 0402  page 13 : A = P3V3_P2V5_P1V8_RVDD ; B = GND
R257  Q_RES  2.2K 5% CHIP  pkg 0402LF  page 27 : A = P3V3_AUX ; B = SMB_BMC_MM7_R_SDA

(kicad_pcb
	(version 20260206)
	(generator "pcbnew")
	(generator_version "10.0")
	(general
		(thickness 1.6)
		(legacy_teardrops no)
	)
	(paper "A4")
	(title_block
		(title "12092022_DA0F0TMDCD0_F0T_Management_Board_D_brd_V3_OCP.brd")
		(comment 1 "Grand Teton / footprints 1384-1385 of 1440")
	)
	(layers
		(0 "F.Cu" signal "TOP")
		(4 "In1.Cu" signal "GND")
		(6 "In2.Cu" signal "IN1")
		(8 "In3.Cu" signal "GND1")
		(10 "In4.Cu" signal "IN2")
		(12 "In5.Cu" signal "VCC")
		(14 "In6.Cu" signal "VCC1")
		(16 "In7.Cu" signal "IN3")
		(18 "In8.Cu" signal "GND2")
		(20 "In9.Cu" signal "IN4")
		(22 "In10.Cu" signal "GND3")
		(2 "B.Cu" signal "BOTTOM")
		(9 "F.Adhes" user "F.Adhesive")
		(11 "B.Adhes" user "B.Adhesive")
		(13 "F.Paste" user "Package Geometry/Pastemask Top")
		(15 "B.Paste" user "Package Geometry/Pastemask Bottom")
		(5 "F.SilkS" user "Ref Des/Silkscreen Top")
		(7 "B.SilkS" user "Ref Des/Silkscreen Bottom")
		(1 "F.Mask" user "Board Geometry/Soldermask Top")
		(3 "B.Mask" user "Board Geometry/Soldermask Bottom")
		(17 "Dwgs.User" user "User.Drawings")
		(19 "Cmts.User" user "User.Comments")
		(21 "Eco1.User" user "User.Eco1")
		(23 "Eco2.User" user "User.Eco2")
		(25 "Edge.Cuts" user "Board Geometry/Outline")
		(27 "Margin" user)
		(31 "F.CrtYd" user "Package Geometry/Place Bound Top")
		(29 "B.CrtYd" user "Package Geometry/Place Bound Bottom")
		(35 "F.Fab" user "Ref Des/Assembly Top")
		(33 "B.Fab" user "Ref Des/Assembly Bottom")
	)
	(footprint ""
		(layer "B.Cu")
		(at 64.036194 -28.356306 -90)
		(property "Reference" "R257"
			(at 0 0 90)
			(layer "B.SilkS")
			(hide yes)
			(effects
				(font
					(size 1.27 1.27)
				)
				(justify mirror)
			)
		)
		(property "Value" ""
			(at 0 0 90)
			(layer "B.Fab")
			(effects
				(font
					(size 1.27 1.27)
				)
				(justify mirror)
			)
		)
		(duplicate_pad_numbers_are_jumpers no)
		(fp_line
			(start -0.7874 0.4064)
			(end 0.7874 0.4064)
			(stroke
				(width 0.1524)
				(type default)
			)
			(layer "B.SilkS")
		)
		(fp_line
			(start 0.7874 0.4064)
			(end 0.7874 -0.4064)
			(stroke
				(width 0.1524)
				(type default)
			)
			(layer "B.SilkS")
		)
		(fp_line
			(start -0.7874 -0.4064)
			(end -0.7874 0.4064)
			(stroke
				(width 0.1524)
				(type default)
			)
			(layer "B.SilkS")
		)
		(fp_line
			(start 0.7874 -0.4064)
			(end -0.7874 -0.4064)
			(stroke
				(width 0.1524)
				(type default)
			)
			(layer "B.SilkS")
		)
		(fp_line
			(start -0.67945 0.3048)
			(end -0.120396 0.3048)
			(stroke
				(width 0.1)
				(type default)
			)
			(layer "B.Fab")
		)
		(fp_line
			(start -0.120396 0.3048)
			(end -0.120396 0.2794)
			(stroke
				(width 0.1)
				(type default)
			)
			(layer "B.Fab")
		)
		(fp_line
			(start 0.12065 0.3048)
			(end 0.67945 0.3048)
			(stroke
				(width 0.1)
				(type default)
			)
			(layer "B.Fab")
		)
		(fp_line
			(start 0.67945 0.3048)
			(end 0.67945 -0.305054)
			(stroke
				(width 0.1)
				(type default)
			)
			(layer "B.Fab")
		)
		(fp_line
			(start -0.120396 0.2794)
			(end 0.12065 0.2794)
			(stroke
				(width 0.1)
				(type default)
			)
			(layer "B.Fab")
		)
		(fp_line
			(start 0.12065 0.2794)
			(end 0.12065 0.3048)
			(stroke
				(width 0.1)
				(type default)
			)
			(layer "B.Fab")
		)
		(fp_line
			(start -0.12065 -0.2794)
			(end -0.12065 -0.3048)
			(stroke
				(width 0.1)
				(type default)
			)
			(layer "B.Fab")
		)
		(fp_line
			(start 0.12065 -0.2794)
			(end -0.12065 -0.2794)
			(stroke
				(width 0.1)
				(type default)
			)
			(layer "B.Fab")
		)
		(fp_line
			(start -0.67945 -0.3048)
			(end -0.67945 0.3048)
			(stroke
				(width 0.1)
				(type default)
			)
			(layer "B.Fab")
		)
		(fp_line
			(start -0.12065 -0.3048)
			(end -0.67945 -0.3048)
			(stroke
				(width 0.1)
				(type default)
			)
			(layer "B.Fab")
		)
		(fp_line
			(start 0.12065 -0.305054)
			(end 0.12065 -0.2794)
			(stroke
				(width 0.1)
				(type default)
			)
			(layer "B.Fab")
		)
		(fp_line
			(start 0.67945 -0.305054)
			(end 0.12065 -0.305054)
			(stroke
				(width 0.1)
				(type default)
			)
			(layer "B.Fab")
		)
		(pad "1" smd circle
			(at 0.40005 0 90)
			(size 0 0)
			(layers "B.Cu" "B.Mask" "B.Paste")
			(net "P3V3_AUX")
		)
		(pad "2" smd circle
			(at -0.40005 0 90)
			(size 0 0)
			(layers "B.Cu" "B.Mask" "B.Paste")
			(net "SMB_BMC_MM7_R_SDA")
		)
	)
	(footprint ""
		(layer "B.Cu")
		(at 47.649384 -47.96409 -90)
		(property "Reference" "C31"
			(at 0 0 90)
			(layer "B.SilkS")
			(hide yes)
			(effects
				(font
					(size 1.27 1.27)
				)
				(justify mirror)
			)
		)
		(property "Value" ""
			(at 0 0 90)
			(layer "B.Fab")
			(effects
				(font
					(size 1.27 1.27)
				)
				(justify mirror)
			)
		)
		(duplicate_pad_numbers_are_jumpers no)
		(fp_line
			(start -0.7874 0.4064)
			(end 0.7874 0.4064)
			(stroke
				(width 0.1524)
				(type default)
			)
			(layer "B.SilkS")
		)
		(fp_line
			(start 0.7874 0.4064)
			(end 0.7874 -0.4064)
			(stroke
				(width 0.1524)
				(type default)
			)
			(layer "B.SilkS")
		)
		(fp_line
			(start -0.7874 -0.4064)
			(end -0.7874 0.4064)
			(stroke
				(width 0.1524)
				(type default)
			)
			(layer "B.SilkS")
		)
		(fp_line
			(start 0.7874 -0.4064)
			(end -0.7874 -0.4064)
			(stroke
				(width 0.1524)
				(type default)
			)
			(layer "B.SilkS")
		)
		(fp_line
			(start -0.67945 0.3048)
			(end -0.120396 0.3048)
			(stroke
				(width 0.1)
				(type default)
			)
			(layer "B.Fab")
		)
		(fp_line
			(start -0.120396 0.3048)
			(end -0.120396 0.2794)
			(stroke
				(width 0.1)
				(type default)
			)
			(layer "B.Fab")
		)
		(fp_line
			(start 0.12065 0.3048)
			(end 0.67945 0.3048)
			(stroke
				(width 0.1)
				(type default)
			)
			(layer "B.Fab")
		)
		(fp_line
			(start 0.67945 0.3048)
			(end 0.67945 -0.305054)
			(stroke
				(width 0.1)
				(type default)
			)
			(layer "B.Fab")
		)
		(fp_line
			(start -0.120396 0.2794)
			(end 0.12065 0.2794)
			(stroke
				(width 0.1)
				(type default)
			)
			(layer "B.Fab")
		)
		(fp_line
			(start 0.12065 0.2794)
			(end 0.12065 0.3048)
			(stroke
				(width 0.1)
				(type default)
			)
			(layer "B.Fab")
		)
		(fp_line
			(start -0.12065 -0.2794)
			(end -0.12065 -0.3048)
			(stroke
				(width 0.1)
				(type default)
			)
			(layer "B.Fab")
		)
		(fp_line
			(start 0.12065 -0.2794)
			(end -0.12065 -0.2794)
			(stroke
				(width 0.1)
				(type default)
			)
			(layer "B.Fab")
		)
		(fp_line
			(start -0.67945 -0.3048)
			(end -0.67945 0.3048)
			(stroke
				(width 0.1)
				(type default)
			)
			(layer "B.Fab")
		)
		(fp_line
			(start -0.12065 -0.3048)
			(end -0.67945 -0.3048)
			(stroke
				(width 0.1)
				(type default)
			)
			(layer "B.Fab")
		)
		(fp_line
			(start 0.12065 -0.305054)
			(end 0.12065 -0.2794)
			(stroke
				(width 0.1)
				(type default)
			)
			(layer "B.Fab")
		)
		(fp_line
			(start 0.67945 -0.305054)
			(end 0.12065 -0.305054)
			(stroke
				(width 0.1)
				(type default)
			)
			(layer "B.Fab")
		)
		(pad "1" smd circle
			(at 0.40005 0 90)
			(size 0 0)
			(layers "B.Cu" "B.Mask" "B.Paste")
			(net "P3V3_P2V5_P1V8_RVDD")
		)
		(pad "2" smd circle
			(at -0.40005 0 90)
			(size 0 0)
			(layers "B.Cu" "B.Mask" "B.Paste")
			(net "GND")
		)
	)
)
